# S9S_MB_2U (Grand Teton) — schematic netlist excerpt (pin names and nets, part order shuffled) for the footprints in the layout excerpt that follows; sources: Cadence DE-HDL packaged netlist, KiCad conversion of 03242023_DA0F0TMBIJ0_F0T_Motherboard_J_brd_V01_OCP.brd

R2234  Q_RES  10K 1% EMPTY  pkg 0402LF  page 195 : A = P1V05_PCH_AUX ; B = FM_BOARD_SKU_ID4
R3321  Q_RES  4.7K 5% CHIP  pkg 0402LF  page 148 : A = P3V3_AUX ; B = GPU_FPGA_READY_ISO

(kicad_pcb
	(version 20260206)
	(generator "pcbnew")
	(generator_version "10.0")
	(general
		(thickness 1.6)
		(legacy_teardrops no)
	)
	(paper "A4")
	(title_block
		(title "03242023_DA0F0TMBIJ0_F0T_Motherboard_J_brd_V01_OCP.brd")
		(comment 1 "Grand Teton / footprints 2484-2485 of 6105")
	)
	(layers
		(0 "F.Cu" signal "TOP")
		(4 "In1.Cu" signal "GND")
		(6 "In2.Cu" signal "IN1")
		(8 "In3.Cu" signal "GND1")
		(10 "In4.Cu" signal "IN2")
		(12 "In5.Cu" signal "GND2")
		(14 "In6.Cu" signal "IN3")
		(16 "In7.Cu" signal "GND3")
		(18 "In8.Cu" signal "VCC")
		(20 "In9.Cu" signal "VCC1")
		(22 "In10.Cu" signal "GND4")
		(24 "In11.Cu" signal "IN4")
		(26 "In12.Cu" signal "GND5")
		(28 "In13.Cu" signal "IN5")
		(30 "In14.Cu" signal "GND6")
		(32 "In15.Cu" signal "IN6")
		(34 "In16.Cu" signal "GND7")
		(2 "B.Cu" signal "BOTTOM")
		(9 "F.Adhes" user "F.Adhesive")
		(11 "B.Adhes" user "B.Adhesive")
		(13 "F.Paste" user "Package Geometry/Pastemask Top")
		(15 "B.Paste" user "Package Geometry/Pastemask Bottom")
		(5 "F.SilkS" user "Ref Des/Silkscreen Top")
		(7 "B.SilkS" user "Ref Des/Silkscreen Bottom")
		(1 "F.Mask" user "Board Geometry/Soldermask Top")
		(3 "B.Mask" user "Board Geometry/Soldermask Bottom")
		(17 "Dwgs.User" user "User.Drawings")
		(19 "Cmts.User" user "User.Comments")
		(21 "Eco1.User" user "User.Eco1")
		(23 "Eco2.User" user "User.Eco2")
		(25 "Edge.Cuts" user "Board Geometry/Outline")
		(27 "Margin" user)
		(31 "F.CrtYd" user "Package Geometry/Place Bound Top")
		(29 "B.CrtYd" user "Package Geometry/Place Bound Bottom")
		(35 "F.Fab" user "Ref Des/Assembly Top")
		(33 "B.Fab" user "Ref Des/Assembly Bottom")
	)
	(footprint ""
		(layer "F.Cu")
		(at 319.8241 -76.585064 -90)
		(property "Reference" "R2234"
			(at 0 0 270)
			(layer "F.SilkS")
			(hide yes)
			(effects
				(font
					(size 1.27 1.27)
				)
			)
		)
		(property "Value" ""
			(at 0 0 270)
			(layer "F.Fab")
			(effects
				(font
					(size 1.27 1.27)
				)
			)
		)
		(duplicate_pad_numbers_are_jumpers no)
		(fp_line
			(start -0.7874 0.4064)
			(end -0.7874 -0.4064)
			(stroke
				(width 0.1524)
				(type default)
			)
			(layer "F.SilkS")
		)
		(fp_line
			(start 0.7874 0.4064)
			(end -0.7874 0.4064)
			(stroke
				(width 0.1524)
				(type default)
			)
			(layer "F.SilkS")
		)
		(fp_line
			(start -0.7874 -0.4064)
			(end 0.7874 -0.4064)
			(stroke
				(width 0.1524)
				(type default)
			)
			(layer "F.SilkS")
		)
		(fp_line
			(start 0.7874 -0.4064)
			(end 0.7874 0.4064)
			(stroke
				(width 0.1524)
				(type default)
			)
			(layer "F.SilkS")
		)
		(fp_line
			(start -0.67945 0.3048)
			(end -0.67945 -0.305054)
			(stroke
				(width 0.1)
				(type default)
			)
			(layer "F.Fab")
		)
		(fp_line
			(start -0.12065 0.3048)
			(end -0.67945 0.3048)
			(stroke
				(width 0.1)
				(type default)
			)
			(layer "F.Fab")
		)
		(fp_line
			(start 0.120396 0.3048)
			(end 0.120396 0.2794)
			(stroke
				(width 0.1)
				(type default)
			)
			(layer "F.Fab")
		)
		(fp_line
			(start 0.67945 0.3048)
			(end 0.120396 0.3048)
			(stroke
				(width 0.1)
				(type default)
			)
			(layer "F.Fab")
		)
		(fp_line
			(start -0.12065 0.2794)
			(end -0.12065 0.3048)
			(stroke
				(width 0.1)
				(type default)
			)
			(layer "F.Fab")
		)
		(fp_line
			(start 0.120396 0.2794)
			(end -0.12065 0.2794)
			(stroke
				(width 0.1)
				(type default)
			)
			(layer "F.Fab")
		)
		(fp_line
			(start -0.12065 -0.2794)
			(end 0.12065 -0.2794)
			(stroke
				(width 0.1)
				(type default)
			)
			(layer "F.Fab")
		)
		(fp_line
			(start 0.12065 -0.2794)
			(end 0.12065 -0.3048)
			(stroke
				(width 0.1)
				(type default)
			)
			(layer "F.Fab")
		)
		(fp_line
			(start 0.12065 -0.3048)
			(end 0.67945 -0.3048)
			(stroke
				(width 0.1)
				(type default)
			)
			(layer "F.Fab")
		)
		(fp_line
			(start 0.67945 -0.3048)
			(end 0.67945 0.3048)
			(stroke
				(width 0.1)
				(type default)
			)
			(layer "F.Fab")
		)
		(fp_line
			(start -0.67945 -0.305054)
			(end -0.12065 -0.305054)
			(stroke
				(width 0.1)
				(type default)
			)
			(layer "F.Fab")
		)
		(fp_line
			(start -0.12065 -0.305054)
			(end -0.12065 -0.2794)
			(stroke
				(width 0.1)
				(type default)
			)
			(layer "F.Fab")
		)
		(pad "1" smd circle
			(at -0.40005 0 270)
			(size 0 0)
			(layers "F.Cu" "F.Mask" "F.Paste")
			(net "P1V05_PCH_AUX")
		)
		(pad "2" smd circle
			(at 0.40005 0 270)
			(size 0 0)
			(layers "F.Cu" "F.Mask" "F.Paste")
			(net "FM_BOARD_SKU_ID4")
		)
	)
	(footprint ""
		(layer "F.Cu")
		(at 24.050752 -401.790408)
		(property "Reference" "R3321"
			(at 0 0 0)
			(layer "F.SilkS")
			(hide yes)
			(effects
				(font
					(size 1.27 1.27)
				)
			)
		)
		(property "Value" ""
			(at 0 0 0)
			(layer "F.Fab")
			(effects
				(font
					(size 1.27 1.27)
				)
			)
		)
		(duplicate_pad_numbers_are_jumpers no)
		(fp_line
			(start -0.7874 -0.4064)
			(end 0.7874 -0.4064)
			(stroke
				(width 0.1524)
				(type default)
			)
			(layer "F.SilkS")
		)
		(fp_line
			(start -0.7874 0.4064)
			(end -0.7874 -0.4064)
			(stroke
				(width 0.1524)
				(type default)
			)
			(layer "F.SilkS")
		)
		(fp_line
			(start 0.7874 -0.4064)
			(end 0.7874 0.4064)
			(stroke
				(width 0.1524)
				(type default)
			)
			(layer "F.SilkS")
		)
		(fp_line
			(start 0.7874 0.4064)
			(end -0.7874 0.4064)
			(stroke
				(width 0.1524)
				(type default)
			)
			(layer "F.SilkS")
		)
		(fp_line
			(start -0.67945 -0.305054)
			(end -0.12065 -0.305054)
			(stroke
				(width 0.1)
				(type default)
			)
			(layer "F.Fab")
		)
		(fp_line
			(start -0.67945 0.3048)
			(end -0.67945 -0.305054)
			(stroke
				(width 0.1)
				(type default)
			)
			(layer "F.Fab")
		)
		(fp_line
			(start -0.12065 -0.305054)
			(end -0.12065 -0.2794)
			(stroke
				(width 0.1)
				(type default)
			)
			(layer "F.Fab")
		)
		(fp_line
			(start -0.12065 -0.2794)
			(end 0.12065 -0.2794)
			(stroke
				(width 0.1)
				(type default)
			)
			(layer "F.Fab")
		)
		(fp_line
			(start -0.12065 0.2794)
			(end -0.12065 0.3048)
			(stroke
				(width 0.1)
				(type default)
			)
			(layer "F.Fab")
		)
		(fp_line
			(start -0.12065 0.3048)
			(end -0.67945 0.3048)
			(stroke
				(width 0.1)
				(type default)
			)
			(layer "F.Fab")
		)
		(fp_line
			(start 0.120396 0.2794)
			(end -0.12065 0.2794)
			(stroke
				(width 0.1)
				(type default)
			)
			(layer "F.Fab")
		)
		(fp_line
			(start 0.120396 0.3048)
			(end 0.120396 0.2794)
			(stroke
				(width 0.1)
				(type default)
			)
			(layer "F.Fab")
		)
		(fp_line
			(start 0.12065 -0.3048)
			(end 0.67945 -0.3048)
			(stroke
				(width 0.1)
				(type default)
			)
			(layer "F.Fab")
		)
		(fp_line
			(start 0.12065 -0.2794)
			(end 0.12065 -0.3048)
			(stroke
				(width 0.1)
				(type default)
			)
			(layer "F.Fab")
		)
		(fp_line
			(start 0.67945 -0.3048)
			(end 0.67945 0.3048)
			(stroke
				(width 0.1)
				(type default)
			)
			(layer "F.Fab")
		)
		(fp_line
			(start 0.67945 0.3048)
			(end 0.120396 0.3048)
			(stroke
				(width 0.1)
				(type default)
			)
			(layer "F.Fab")
		)
		(pad "1" smd circle
			(at -0.40005 0)
			(size 0 0)
			(layers "F.Cu" "F.Mask" "F.Paste")
			(net "P3V3_AUX")
		)
		(pad "2" smd circle
			(at 0.40005 0)
			(size 0 0)
			(layers "F.Cu" "F.Mask" "F.Paste")
			(net "GPU_FPGA_READY_ISO")
		)
	)
)
